FILE_TYPE=LIBRARY_PARTS;
primitive 'NCP3232L','NCP3232L_SM';
  pin
    'AGND':
      PIN_NUMBER='(5)';
      PINUSE='GROUND';
      NO_LOAD_CHECK='Both';
      NO_IO_CHECK='Both';
      NO_ASSERT_CHECK='TRUE';
      NO_DIR_CHECK='TRUE';
      ALLOW_CONNECT='TRUE';
    'BST':
      PIN_NUMBER='(36)';
      INPUT_LOAD='(-0.01,0.01)';
    'COMP':
      PIN_NUMBER='(3)';
      OUTPUT_LOAD='(1.0,-1.0)';
    'EN':
      PIN_NUMBER='(40)';
      INPUT_LOAD='(-0.01,0.01)';
    'FB':
      PIN_NUMBER='(2)';
      BIDIRECTIONAL='TRUE';
      INPUT_LOAD='(-0.01,0.01)';
      OUTPUT_LOAD='(1.0,-1.0)';
    'GND':
      PIN_NUMBER='(41)';
      PINUSE='GROUND';
      NO_LOAD_CHECK='Both';
      NO_IO_CHECK='Both';
      NO_ASSERT_CHECK='TRUE';
      NO_DIR_CHECK='TRUE';
      ALLOW_CONNECT='TRUE';
    'ISET':
      PIN_NUMBER='(4)';
      BIDIRECTIONAL='TRUE';
      INPUT_LOAD='(-0.01,0.01)';
      OUTPUT_LOAD='(1.0,-1.0)';
    'OTS':
      PIN_NUMBER='(6)';
      INPUT_LOAD='(-0.01,0.01)';
    'PG':
      PIN_NUMBER='(7)';
      BIDIRECTIONAL='TRUE';
      INPUT_LOAD='(-0.01,0.01)';
      OUTPUT_LOAD='(1.0,-1.0)';
    'PGND'<13>:
      PIN_NUMBER='(37)';
      PINUSE='GROUND';
      NO_LOAD_CHECK='Both';
      NO_IO_CHECK='Both';
      NO_ASSERT_CHECK='TRUE';
      NO_DIR_CHECK='TRUE';
      ALLOW_CONNECT='TRUE';
    'PGND'<12>:
      PIN_NUMBER='(28)';
      PINUSE='GROUND';
      NO_LOAD_CHECK='Both';
      NO_IO_CHECK='Both';
      NO_ASSERT_CHECK='TRUE';
      NO_DIR_CHECK='TRUE';
      ALLOW_CONNECT='TRUE';
    'PGND'<11>:
      PIN_NUMBER='(27)';
      PINUSE='GROUND';
      NO_LOAD_CHECK='Both';
      NO_IO_CHECK='Both';
      NO_ASSERT_CHECK='TRUE';
      NO_DIR_CHECK='TRUE';
      ALLOW_CONNECT='TRUE';
    'PGND'<10>:
      PIN_NUMBER='(26)';
      PINUSE='GROUND';
      NO_LOAD_CHECK='Both';
      NO_IO_CHECK='Both';
      NO_ASSERT_CHECK='TRUE';
      NO_DIR_CHECK='TRUE';
      ALLOW_CONNECT='TRUE';
    'PGND'<9>:
      PIN_NUMBER='(25)';
      PINUSE='GROUND';
      NO_LOAD_CHECK='Both';
      NO_IO_CHECK='Both';
      NO_ASSERT_CHECK='TRUE';
      NO_DIR_CHECK='TRUE';
      ALLOW_CONNECT='TRUE';
    'PGND'<8>:
      PIN_NUMBER='(24)';
      PINUSE='GROUND';
      NO_LOAD_CHECK='Both';
      NO_IO_CHECK='Both';
      NO_ASSERT_CHECK='TRUE';
      NO_DIR_CHECK='TRUE';
      ALLOW_CONNECT='TRUE';
    'PGND'<7>:
      PIN_NUMBER='(23)';
      PINUSE='GROUND';
      NO_LOAD_CHECK='Both';
      NO_IO_CHECK='Both';
      NO_ASSERT_CHECK='TRUE';
      NO_DIR_CHECK='TRUE';
      ALLOW_CONNECT='TRUE';
    'PGND'<6>:
      PIN_NUMBER='(22)';
      PINUSE='GROUND';
      NO_LOAD_CHECK='Both';
      NO_IO_CHECK='Both';
      NO_ASSERT_CHECK='TRUE';
      NO_DIR_CHECK='TRUE';
      ALLOW_CONNECT='TRUE';
    'PGND'<5>:
      PIN_NUMBER='(21)';
      PINUSE='GROUND';
      NO_LOAD_CHECK='Both';
      NO_IO_CHECK='Both';
      NO_ASSERT_CHECK='TRUE';
      NO_DIR_CHECK='TRUE';
      ALLOW_CONNECT='TRUE';
    'PGND'<4>:
      PIN_NUMBER='(20)';
      PINUSE='GROUND';
      NO_LOAD_CHECK='Both';
      NO_IO_CHECK='Both';
      NO_ASSERT_CHECK='TRUE';
      NO_DIR_CHECK='TRUE';
      ALLOW_CONNECT='TRUE';
    'PGND'<3>:
      PIN_NUMBER='(19)';
      PINUSE='GROUND';
      NO_LOAD_CHECK='Both';
      NO_IO_CHECK='Both';
      NO_ASSERT_CHECK='TRUE';
      NO_DIR_CHECK='TRUE';
      ALLOW_CONNECT='TRUE';
    'PGND'<2>:
      PIN_NUMBER='(18)';
      PINUSE='GROUND';
      NO_LOAD_CHECK='Both';
      NO_IO_CHECK='Both';
      NO_ASSERT_CHECK='TRUE';
      NO_DIR_CHECK='TRUE';
      ALLOW_CONNECT='TRUE';
    'PGND'<1>:
      PIN_NUMBER='(17)';
      PINUSE='GROUND';
      NO_LOAD_CHECK='Both';
      NO_IO_CHECK='Both';
      NO_ASSERT_CHECK='TRUE';
      NO_DIR_CHECK='TRUE';
      ALLOW_CONNECT='TRUE';
    'PGND'<0>:
      PIN_NUMBER='(16)';
      PINUSE='GROUND';
      NO_LOAD_CHECK='Both';
      NO_IO_CHECK='Both';
      NO_ASSERT_CHECK='TRUE';
      NO_DIR_CHECK='TRUE';
      ALLOW_CONNECT='TRUE';
    'SS':
      PIN_NUMBER='(1)';
      BIDIRECTIONAL='TRUE';
      INPUT_LOAD='(-0.01,0.01)';
      OUTPUT_LOAD='(1.0,-1.0)';
    'VB':
      PIN_NUMBER='(38)';
      OUTPUT_LOAD='(1.0,-1.0)';
    'VCC':
      PIN_NUMBER='(39)';
      PINUSE='POWER';
      NO_LOAD_CHECK='Both';
      NO_IO_CHECK='Both';
      NO_ASSERT_CHECK='TRUE';
      NO_DIR_CHECK='TRUE';
      ALLOW_CONNECT='TRUE';
    'VIN'<7>:
      PIN_NUMBER='(42)';
      INPUT_LOAD='(-0.01,0.01)';
    'VIN'<6>:
      PIN_NUMBER='(14)';
      INPUT_LOAD='(-0.01,0.01)';
    'VIN'<5>:
      PIN_NUMBER='(13)';
      INPUT_LOAD='(-0.01,0.01)';
    'VIN'<4>:
      PIN_NUMBER='(12)';
      INPUT_LOAD='(-0.01,0.01)';
    'VIN'<3>:
      PIN_NUMBER='(11)';
      INPUT_LOAD='(-0.01,0.01)';
    'VIN'<2>:
      PIN_NUMBER='(10)';
      INPUT_LOAD='(-0.01,0.01)';
    'VIN'<1>:
      PIN_NUMBER='(9)';
      INPUT_LOAD='(-0.01,0.01)';
    'VIN'<0>:
      PIN_NUMBER='(8)';
      INPUT_LOAD='(-0.01,0.01)';
    'VSW':
      PIN_NUMBER='(35)';
      BIDIRECTIONAL='TRUE';
      INPUT_LOAD='(-0.01,0.01)';
      OUTPUT_LOAD='(1.0,-1.0)';
    'VSWH'<7>:
      PIN_NUMBER='(43)';
      BIDIRECTIONAL='TRUE';
      INPUT_LOAD='(-0.01,0.01)';
      OUTPUT_LOAD='(1.0,-1.0)';
    'VSWH'<6>:
      PIN_NUMBER='(34)';
      BIDIRECTIONAL='TRUE';
      INPUT_LOAD='(-0.01,0.01)';
      OUTPUT_LOAD='(1.0,-1.0)';
    'VSWH'<5>:
      PIN_NUMBER='(33)';
      BIDIRECTIONAL='TRUE';
      INPUT_LOAD='(-0.01,0.01)';
      OUTPUT_LOAD='(1.0,-1.0)';
    'VSWH'<4>:
      PIN_NUMBER='(32)';
      BIDIRECTIONAL='TRUE';
      INPUT_LOAD='(-0.01,0.01)';
      OUTPUT_LOAD='(1.0,-1.0)';
    'VSWH'<3>:
      PIN_NUMBER='(31)';
      BIDIRECTIONAL='TRUE';
      INPUT_LOAD='(-0.01,0.01)';
      OUTPUT_LOAD='(1.0,-1.0)';
    'VSWH'<2>:
      PIN_NUMBER='(30)';
      BIDIRECTIONAL='TRUE';
      INPUT_LOAD='(-0.01,0.01)';
      OUTPUT_LOAD='(1.0,-1.0)';
    'VSWH'<1>:
      PIN_NUMBER='(29)';
      BIDIRECTIONAL='TRUE';
      INPUT_LOAD='(-0.01,0.01)';
      OUTPUT_LOAD='(1.0,-1.0)';
    'VSWH'<0>:
      PIN_NUMBER='(15)';
      BIDIRECTIONAL='TRUE';
      INPUT_LOAD='(-0.01,0.01)';
      OUTPUT_LOAD='(1.0,-1.0)';
  end_pin;
  body
    PART_NAME='NCP3232L';
    BODY_NAME='NCP3232L';
    PHYS_DES_PREFIX='EU';
  end_body;
end_primitive;

END.
